(kicad_pcb
	(version 20260206)
	(generator "pcbnew")
	(generator_version "10.0")
	(general
		(thickness 1.6)
		(legacy_teardrops no)
	)
	(paper "A4")
	(title_block
		(title "peb — Lightning_PEB_BRD.brd")
		(comment 1 "Lightning (Wiwynn / Facebook NVMe JBOF) / footprints 1102-1108 of 2563")
	)
	(layers
		(0 "F.Cu" signal "TOP")
		(4 "In1.Cu" signal "L2GND")
		(6 "In2.Cu" signal "L3")
		(8 "In3.Cu" signal "L4VCC")
		(10 "In4.Cu" signal "L5VCC")
		(12 "In5.Cu" signal "L6")
		(14 "In6.Cu" signal "L7GND")
		(2 "B.Cu" signal "BOTTOM")
		(9 "F.Adhes" user "F.Adhesive")
		(11 "B.Adhes" user "B.Adhesive")
		(13 "F.Paste" user "Package Geometry/Pastemask Top")
		(15 "B.Paste" user "Package Geometry/Pastemask Bottom")
		(5 "F.SilkS" user "Ref Des/Silkscreen Top")
		(7 "B.SilkS" user "Ref Des/Silkscreen Bottom")
		(1 "F.Mask" user "Board Geometry/Soldermask Top")
		(3 "B.Mask" user "Board Geometry/Soldermask Bottom")
		(17 "Dwgs.User" user "User.Drawings")
		(19 "Cmts.User" user "User.Comments")
		(21 "Eco1.User" user "User.Eco1")
		(23 "Eco2.User" user "User.Eco2")
		(25 "Edge.Cuts" user "Board Geometry/Outline")
		(27 "Margin" user)
		(31 "F.CrtYd" user "Package Geometry/Place Bound Top")
		(29 "B.CrtYd" user "Package Geometry/Place Bound Bottom")
		(35 "F.Fab" user "Ref Des/Assembly Top")
		(33 "B.Fab" user "Ref Des/Assembly Bottom")
	)
	(footprint ""
		(layer "F.Cu")
		(at 258.050792 -26.289 180)
		(property "Reference" "R741"
			(at 0 0 180)
			(layer "F.SilkS")
			(hide yes)
			(effects
				(font
					(size 1.27 1.27)
				)
			)
		)
		(property "Value" "4K7R2F-GP"
			(at 0.064008 -3.993896 180)
			(unlocked yes)
			(layer "F.Fab")
			(hide yes)
			(effects
				(font
					(size 1.016 1.016)
					(thickness 0.1524)
				)
			)
		)
		(property "Device Type" "R402H16"
			(at 0.064008 -5.517896 180)
			(unlocked yes)
			(layer "F.Fab")
			(hide yes)
			(effects
				(font
					(size 1.016 1.016)
					(thickness 0.1524)
				)
			)
		)
		(duplicate_pad_numbers_are_jumpers no)
		(fp_line
			(start 0.508 -0.9398)
			(end -0.508 -0.9398)
			(stroke
				(width 0.1524)
				(type default)
			)
			(layer "F.SilkS")
		)
		(fp_line
			(start -0.508 -0.9398)
			(end -0.508 0.9398)
			(stroke
				(width 0.1524)
				(type default)
			)
			(layer "F.SilkS")
		)
		(fp_rect
			(start -0.508 0.9398)
			(end 0.508 -0.9398)
			(stroke
				(width 0)
				(type default)
			)
			(fill no)
			(layer "F.CrtYd")
		)
		(fp_rect
			(start -0.508 0.9398)
			(end 0.508 -0.9398)
			(stroke
				(width 0)
				(type default)
			)
			(fill no)
			(layer "F.Fab")
		)
		(pad "1" smd custom
			(at 0 -0.4445 180)
			(size 0.1397 0.1397)
			(layers "F.Cu" "F.Mask" "F.Paste")
			(net "P3V3_GPIO")
			(options
				(clearance outline)
				(anchor circle)
			)
			(primitives
				(gr_poly
					(pts
						(arc
							(start -0.1778 -0.2794)
							(mid -0.249642 -0.249642)
							(end -0.2794 -0.1778)
						)
						(arc
							(start -0.2794 0.1778)
							(mid -0.249642 0.249642)
							(end -0.1778 0.2794)
						)
						(arc
							(start 0.1778 0.2794)
							(mid 0.249642 0.249642)
							(end 0.2794 0.1778)
						)
						(arc
							(start 0.2794 -0.1778)
							(mid 0.249642 -0.249642)
							(end 0.1778 -0.2794)
						)
					)
					(width 0)
					(fill yes)
				)
			)
		)
		(pad "2" smd custom
			(at 0 0.4445 180)
			(size 0.1397 0.1397)
			(layers "F.Cu" "F.Mask" "F.Paste")
			(net "IOEXP_INT#_2")
			(options
				(clearance outline)
				(anchor circle)
			)
			(primitives
				(gr_poly
					(pts
						(arc
							(start -0.1778 -0.2794)
							(mid -0.249642 -0.249642)
							(end -0.2794 -0.1778)
						)
						(arc
							(start -0.2794 0.1778)
							(mid -0.249642 0.249642)
							(end -0.1778 0.2794)
						)
						(arc
							(start 0.1778 0.2794)
							(mid 0.249642 0.249642)
							(end 0.2794 0.1778)
						)
						(arc
							(start 0.2794 -0.1778)
							(mid 0.249642 -0.249642)
							(end 0.1778 -0.2794)
						)
					)
					(width 0)
					(fill yes)
				)
			)
		)
	)
	(footprint ""
		(layer "F.Cu")
		(at 53.721 -135.763 90)
		(property "Reference" "R151"
			(at 0 0 90)
			(layer "F.SilkS")
			(hide yes)
			(effects
				(font
					(size 1.27 1.27)
				)
			)
		)
		(property "Value" "4K7R2F-GP"
			(at 0.064008 -3.993896 90)
			(unlocked yes)
			(layer "F.Fab")
			(hide yes)
			(effects
				(font
					(size 1.016 1.016)
					(thickness 0.1524)
				)
			)
		)
		(property "Device Type" "R402H16"
			(at 0.064008 -5.517896 90)
			(unlocked yes)
			(layer "F.Fab")
			(hide yes)
			(effects
				(font
					(size 1.016 1.016)
					(thickness 0.1524)
				)
			)
		)
		(duplicate_pad_numbers_are_jumpers no)
		(fp_line
			(start 0.508 -0.9398)
			(end -0.508 -0.9398)
			(stroke
				(width 0.1524)
				(type default)
			)
			(layer "F.SilkS")
		)
		(fp_line
			(start -0.508 -0.9398)
			(end -0.508 0.9398)
			(stroke
				(width 0.1524)
				(type default)
			)
			(layer "F.SilkS")
		)
		(fp_rect
			(start -0.508 0.9398)
			(end 0.508 -0.9398)
			(stroke
				(width 0)
				(type default)
			)
			(fill no)
			(layer "F.CrtYd")
		)
		(fp_rect
			(start -0.508 0.9398)
			(end 0.508 -0.9398)
			(stroke
				(width 0)
				(type default)
			)
			(fill no)
			(layer "F.Fab")
		)
		(pad "1" smd custom
			(at 0 -0.4445 90)
			(size 0.1397 0.1397)
			(layers "F.Cu" "F.Mask" "F.Paste")
			(net "CBL_PRSNT_N_1")
			(options
				(clearance outline)
				(anchor circle)
			)
			(primitives
				(gr_poly
					(pts
						(arc
							(start -0.1778 -0.2794)
							(mid -0.249642 -0.249642)
							(end -0.2794 -0.1778)
						)
						(arc
							(start -0.2794 0.1778)
							(mid -0.249642 0.249642)
							(end -0.1778 0.2794)
						)
						(arc
							(start 0.1778 0.2794)
							(mid 0.249642 0.249642)
							(end 0.2794 0.1778)
						)
						(arc
							(start 0.2794 -0.1778)
							(mid 0.249642 -0.249642)
							(end 0.1778 -0.2794)
						)
					)
					(width 0)
					(fill yes)
				)
			)
		)
		(pad "2" smd custom
			(at 0 0.4445 90)
			(size 0.1397 0.1397)
			(layers "F.Cu" "F.Mask" "F.Paste")
			(net "P3V3_STBY")
			(options
				(clearance outline)
				(anchor circle)
			)
			(primitives
				(gr_poly
					(pts
						(arc
							(start -0.1778 -0.2794)
							(mid -0.249642 -0.249642)
							(end -0.2794 -0.1778)
						)
						(arc
							(start -0.2794 0.1778)
							(mid -0.249642 0.249642)
							(end -0.1778 0.2794)
						)
						(arc
							(start 0.1778 0.2794)
							(mid 0.249642 0.249642)
							(end 0.2794 0.1778)
						)
						(arc
							(start 0.2794 -0.1778)
							(mid 0.249642 -0.249642)
							(end 0.1778 -0.2794)
						)
					)
					(width 0)
					(fill yes)
				)
			)
		)
	)
	(footprint ""
		(layer "F.Cu")
		(at 17.399 -107.315)
		(property "Reference" "PC78"
			(at 0 0 0)
			(layer "F.SilkS")
			(hide yes)
			(effects
				(font
					(size 1.27 1.27)
				)
			)
		)
		(property "Value" "SCD01U25V2KX-3GP"
			(at 1.1811 -2.7051 0)
			(unlocked yes)
			(layer "F.Fab")
			(hide yes)
			(effects
				(font
					(size 1.016 1.016)
					(thickness 0.1524)
				)
			)
		)
		(property "Device Type" "C402H22"
			(at 1.1811 -4.2291 0)
			(unlocked yes)
			(layer "F.Fab")
			(hide yes)
			(effects
				(font
					(size 1.016 1.016)
					(thickness 0.1524)
				)
			)
		)
		(duplicate_pad_numbers_are_jumpers no)
		(fp_rect
			(start -0.4318 0.9525)
			(end 0.4318 -0.9525)
			(stroke
				(width 0)
				(type default)
			)
			(fill no)
			(layer "F.CrtYd")
		)
		(fp_rect
			(start -0.4318 0.9525)
			(end 0.4318 -0.9525)
			(stroke
				(width 0)
				(type default)
			)
			(fill no)
			(layer "F.Fab")
		)
		(pad "1" smd custom
			(at 0 -0.4445)
			(size 0.1524 0.1524)
			(layers "F.Cu" "F.Mask" "F.Paste")
			(net "P1V26_PWR")
			(options
				(clearance outline)
				(anchor circle)
			)
			(primitives
				(gr_poly
					(pts
						(arc
							(start 0.3048 -0.2032)
							(mid 0.275042 -0.275042)
							(end 0.2032 -0.3048)
						)
						(arc
							(start -0.2032 -0.3048)
							(mid -0.275042 -0.275042)
							(end -0.3048 -0.2032)
						)
						(arc
							(start -0.3048 0.2032)
							(mid -0.275042 0.275042)
							(end -0.2032 0.3048)
						)
						(arc
							(start 0.2032 0.3048)
							(mid 0.275042 0.275042)
							(end 0.3048 0.2032)
						)
					)
					(width 0)
					(fill yes)
				)
			)
		)
		(pad "2" smd custom
			(at 0 0.4445)
			(size 0.1524 0.1524)
			(layers "F.Cu" "F.Mask" "F.Paste")
			(net "VR_P1V26_STBY_FB")
			(options
				(clearance outline)
				(anchor circle)
			)
			(primitives
				(gr_poly
					(pts
						(arc
							(start 0.3048 -0.2032)
							(mid 0.275042 -0.275042)
							(end 0.2032 -0.3048)
						)
						(arc
							(start -0.2032 -0.3048)
							(mid -0.275042 -0.275042)
							(end -0.3048 -0.2032)
						)
						(arc
							(start -0.3048 0.2032)
							(mid -0.275042 0.275042)
							(end -0.2032 0.3048)
						)
						(arc
							(start 0.2032 0.3048)
							(mid 0.275042 0.275042)
							(end 0.3048 0.2032)
						)
					)
					(width 0)
					(fill yes)
				)
			)
		)
	)
	(footprint ""
		(layer "F.Cu")
		(at 142.247874 -87.11692 90)
		(property "Reference" "PR9034"
			(at 0 0 90)
			(layer "F.SilkS")
			(hide yes)
			(effects
				(font
					(size 1.27 1.27)
				)
			)
		)
		(property "Value" "2K87R2F-1-GP"
			(at 0.064008 -3.993896 90)
			(unlocked yes)
			(layer "F.Fab")
			(hide yes)
			(effects
				(font
					(size 1.016 1.016)
					(thickness 0.1524)
				)
			)
		)
		(property "Device Type" "R402H16"
			(at 0.064008 -5.517896 90)
			(unlocked yes)
			(layer "F.Fab")
			(hide yes)
			(effects
				(font
					(size 1.016 1.016)
					(thickness 0.1524)
				)
			)
		)
		(duplicate_pad_numbers_are_jumpers no)
		(fp_line
			(start 0.508 -0.9398)
			(end -0.508 -0.9398)
			(stroke
				(width 0.1524)
				(type default)
			)
			(layer "F.SilkS")
		)
		(fp_line
			(start -0.508 -0.9398)
			(end -0.508 0.9398)
			(stroke
				(width 0.1524)
				(type default)
			)
			(layer "F.SilkS")
		)
		(fp_rect
			(start -0.508 0.9398)
			(end 0.508 -0.9398)
			(stroke
				(width 0)
				(type default)
			)
			(fill no)
			(layer "F.CrtYd")
		)
		(fp_rect
			(start -0.508 0.9398)
			(end 0.508 -0.9398)
			(stroke
				(width 0)
				(type default)
			)
			(fill no)
			(layer "F.Fab")
		)
		(pad "1" smd custom
			(at 0 -0.4445 90)
			(size 0.1397 0.1397)
			(layers "F.Cu" "F.Mask" "F.Paste")
			(net "VR_P1V8_STBY_FB")
			(options
				(clearance outline)
				(anchor circle)
			)
			(primitives
				(gr_poly
					(pts
						(arc
							(start -0.1778 -0.2794)
							(mid -0.249642 -0.249642)
							(end -0.2794 -0.1778)
						)
						(arc
							(start -0.2794 0.1778)
							(mid -0.249642 0.249642)
							(end -0.1778 0.2794)
						)
						(arc
							(start 0.1778 0.2794)
							(mid 0.249642 0.249642)
							(end 0.2794 0.1778)
						)
						(arc
							(start 0.2794 -0.1778)
							(mid 0.249642 -0.249642)
							(end 0.1778 -0.2794)
						)
					)
					(width 0)
					(fill yes)
				)
			)
		)
		(pad "2" smd custom
			(at 0 0.4445 90)
			(size 0.1397 0.1397)
			(layers "F.Cu" "F.Mask" "F.Paste")
			(net "GND")
			(options
				(clearance outline)
				(anchor circle)
			)
			(primitives
				(gr_poly
					(pts
						(arc
							(start -0.1778 -0.2794)
							(mid -0.249642 -0.249642)
							(end -0.2794 -0.1778)
						)
						(arc
							(start -0.2794 0.1778)
							(mid -0.249642 0.249642)
							(end -0.1778 0.2794)
						)
						(arc
							(start 0.1778 0.2794)
							(mid 0.249642 0.249642)
							(end 0.2794 0.1778)
						)
						(arc
							(start 0.2794 -0.1778)
							(mid 0.249642 -0.249642)
							(end 0.1778 -0.2794)
						)
					)
					(width 0)
					(fill yes)
				)
			)
		)
	)
	(footprint ""
		(layer "F.Cu")
		(at 20.3454 -185.7502 -90)
		(property "Reference" "R2120"
			(at 0 0 270)
			(layer "F.SilkS")
			(hide yes)
			(effects
				(font
					(size 1.27 1.27)
				)
			)
		)
		(property "Value" "10R2F-L-GP"
			(at 0.064008 -3.993896 270)
			(unlocked yes)
			(layer "F.Fab")
			(hide yes)
			(effects
				(font
					(size 1.016 1.016)
					(thickness 0.1524)
				)
			)
		)
		(property "Device Type" "R402H14"
			(at 0.064008 -5.517896 270)
			(unlocked yes)
			(layer "F.Fab")
			(hide yes)
			(effects
				(font
					(size 1.016 1.016)
					(thickness 0.1524)
				)
			)
		)
		(duplicate_pad_numbers_are_jumpers no)
		(fp_line
			(start -0.508 -0.9398)
			(end -0.508 0.9398)
			(stroke
				(width 0.1524)
				(type default)
			)
			(layer "F.SilkS")
		)
		(fp_line
			(start 0.508 -0.9398)
			(end -0.508 -0.9398)
			(stroke
				(width 0.1524)
				(type default)
			)
			(layer "F.SilkS")
		)
		(fp_rect
			(start -0.508 0.9398)
			(end 0.508 -0.9398)
			(stroke
				(width 0)
				(type default)
			)
			(fill no)
			(layer "F.CrtYd")
		)
		(fp_rect
			(start -0.508 0.9398)
			(end 0.508 -0.9398)
			(stroke
				(width 0)
				(type default)
			)
			(fill no)
			(layer "F.Fab")
		)
		(pad "1" smd custom
			(at 0 -0.4445 270)
			(size 0.1397 0.1397)
			(layers "F.Cu" "F.Mask" "F.Paste")
			(net "MB0_CM_SENSE_R1_P")
			(options
				(clearance outline)
				(anchor circle)
			)
			(primitives
				(gr_poly
					(pts
						(arc
							(start -0.1778 -0.2794)
							(mid -0.249642 -0.249642)
							(end -0.2794 -0.1778)
						)
						(arc
							(start -0.2794 0.1778)
							(mid -0.249642 0.249642)
							(end -0.1778 0.2794)
						)
						(arc
							(start 0.1778 0.2794)
							(mid 0.249642 0.249642)
							(end 0.2794 0.1778)
						)
						(arc
							(start 0.2794 -0.1778)
							(mid 0.249642 -0.249642)
							(end 0.1778 -0.2794)
						)
					)
					(width 0)
					(fill yes)
				)
			)
		)
		(pad "2" smd custom
			(at 0 0.4445 270)
			(size 0.1397 0.1397)
			(layers "F.Cu" "F.Mask" "F.Paste")
			(net "ADM1278_HS_P")
			(options
				(clearance outline)
				(anchor circle)
			)
			(primitives
				(gr_poly
					(pts
						(arc
							(start -0.1778 -0.2794)
							(mid -0.249642 -0.249642)
							(end -0.2794 -0.1778)
						)
						(arc
							(start -0.2794 0.1778)
							(mid -0.249642 0.249642)
							(end -0.1778 0.2794)
						)
						(arc
							(start 0.1778 0.2794)
							(mid 0.249642 0.249642)
							(end 0.2794 0.1778)
						)
						(arc
							(start 0.2794 -0.1778)
							(mid 0.249642 -0.249642)
							(end 0.1778 -0.2794)
						)
					)
					(width 0)
					(fill yes)
				)
			)
		)
	)
	(footprint ""
		(layer "F.Cu")
		(at 15.9512 -83.5406)
		(property "Reference" "R401"
			(at 0 0 0)
			(layer "F.SilkS")
			(hide yes)
			(effects
				(font
					(size 1.27 1.27)
				)
			)
		)
		(property "Value" "10KR2F-2-GP"
			(at 0.064008 -3.993896 0)
			(unlocked yes)
			(layer "F.Fab")
			(hide yes)
			(effects
				(font
					(size 1.016 1.016)
					(thickness 0.1524)
				)
			)
		)
		(property "Device Type" "R402H16"
			(at 0.064008 -5.517896 0)
			(unlocked yes)
			(layer "F.Fab")
			(hide yes)
			(effects
				(font
					(size 1.016 1.016)
					(thickness 0.1524)
				)
			)
		)
		(duplicate_pad_numbers_are_jumpers no)
		(fp_line
			(start -0.508 -0.9398)
			(end -0.508 0.9398)
			(stroke
				(width 0.1524)
				(type default)
			)
			(layer "F.SilkS")
		)
		(fp_line
			(start 0.508 -0.9398)
			(end -0.508 -0.9398)
			(stroke
				(width 0.1524)
				(type default)
			)
			(layer "F.SilkS")
		)
		(fp_rect
			(start -0.508 0.9398)
			(end 0.508 -0.9398)
			(stroke
				(width 0)
				(type default)
			)
			(fill no)
			(layer "F.CrtYd")
		)
		(fp_rect
			(start -0.508 0.9398)
			(end 0.508 -0.9398)
			(stroke
				(width 0)
				(type default)
			)
			(fill no)
			(layer "F.Fab")
		)
		(pad "1" smd custom
			(at 0 -0.4445)
			(size 0.1397 0.1397)
			(layers "F.Cu" "F.Mask" "F.Paste")
			(net "P3V3_STBY")
			(options
				(clearance outline)
				(anchor circle)
			)
			(primitives
				(gr_poly
					(pts
						(arc
							(start -0.1778 -0.2794)
							(mid -0.249642 -0.249642)
							(end -0.2794 -0.1778)
						)
						(arc
							(start -0.2794 0.1778)
							(mid -0.249642 0.249642)
							(end -0.1778 0.2794)
						)
						(arc
							(start 0.1778 0.2794)
							(mid 0.249642 0.249642)
							(end 0.2794 0.1778)
						)
						(arc
							(start 0.2794 -0.1778)
							(mid 0.249642 -0.249642)
							(end 0.1778 -0.2794)
						)
					)
					(width 0)
					(fill yes)
				)
			)
		)
		(pad "2" smd custom
			(at 0 0.4445)
			(size 0.1397 0.1397)
			(layers "F.Cu" "F.Mask" "F.Paste")
			(net "FM_PCH_LAN1_DISABLE_N")
			(options
				(clearance outline)
				(anchor circle)
			)
			(primitives
				(gr_poly
					(pts
						(arc
							(start -0.1778 -0.2794)
							(mid -0.249642 -0.249642)
							(end -0.2794 -0.1778)
						)
						(arc
							(start -0.2794 0.1778)
							(mid -0.249642 0.249642)
							(end -0.1778 0.2794)
						)
						(arc
							(start 0.1778 0.2794)
							(mid 0.249642 0.249642)
							(end 0.2794 0.1778)
						)
						(arc
							(start 0.2794 -0.1778)
							(mid 0.249642 -0.249642)
							(end 0.1778 -0.2794)
						)
					)
					(width 0)
					(fill yes)
				)
			)
		)
	)
	(footprint ""
		(layer "F.Cu")
		(at 85.0392 -81.0006 90)
		(property "Reference" "SR947"
			(at 0 0 90)
			(layer "F.SilkS")
			(hide yes)
			(effects
				(font
					(size 1.27 1.27)
				)
			)
		)
		(property "Value" "0R2J-2-GP"
			(at 0.064008 -3.993896 90)
			(unlocked yes)
			(layer "F.Fab")
			(hide yes)
			(effects
				(font
					(size 1.016 1.016)
					(thickness 0.1524)
				)
			)
		)
		(property "Device Type" "R402H16"
			(at 0.064008 -5.517896 90)
			(unlocked yes)
			(layer "F.Fab")
			(hide yes)
			(effects
				(font
					(size 1.016 1.016)
					(thickness 0.1524)
				)
			)
		)
		(duplicate_pad_numbers_are_jumpers no)
		(fp_line
			(start 0.508 -0.9398)
			(end -0.508 -0.9398)
			(stroke
				(width 0.1524)
				(type default)
			)
			(layer "F.SilkS")
		)
		(fp_line
			(start -0.508 -0.9398)
			(end -0.508 0.9398)
			(stroke
				(width 0.1524)
				(type default)
			)
			(layer "F.SilkS")
		)
		(fp_rect
			(start -0.508 0.9398)
			(end 0.508 -0.9398)
			(stroke
				(width 0)
				(type default)
			)
			(fill no)
			(layer "F.CrtYd")
		)
		(fp_rect
			(start -0.508 0.9398)
			(end 0.508 -0.9398)
			(stroke
				(width 0)
				(type default)
			)
			(fill no)
			(layer "F.Fab")
		)
		(pad "1" smd custom
			(at 0 -0.4445 90)
			(size 0.1397 0.1397)
			(layers "F.Cu" "F.Mask" "F.Paste")
			(net "SAS_SMART_R_RX")
			(options
				(clearance outline)
				(anchor circle)
			)
			(primitives
				(gr_poly
					(pts
						(arc
							(start -0.1778 -0.2794)
							(mid -0.249642 -0.249642)
							(end -0.2794 -0.1778)
						)
						(arc
							(start -0.2794 0.1778)
							(mid -0.249642 0.249642)
							(end -0.1778 0.2794)
						)
						(arc
							(start 0.1778 0.2794)
							(mid 0.249642 0.249642)
							(end 0.2794 0.1778)
						)
						(arc
							(start 0.2794 -0.1778)
							(mid 0.249642 -0.249642)
							(end 0.1778 -0.2794)
						)
					)
					(width 0)
					(fill yes)
				)
			)
		)
		(pad "2" smd custom
			(at 0 0.4445 90)
			(size 0.1397 0.1397)
			(layers "F.Cu" "F.Mask" "F.Paste")
			(net "UART_USIN")
			(options
				(clearance outline)
				(anchor circle)
			)
			(primitives
				(gr_poly
					(pts
						(arc
							(start -0.1778 -0.2794)
							(mid -0.249642 -0.249642)
							(end -0.2794 -0.1778)
						)
						(arc
							(start -0.2794 0.1778)
							(mid -0.249642 0.249642)
							(end -0.1778 0.2794)
						)
						(arc
							(start 0.1778 0.2794)
							(mid 0.249642 0.249642)
							(end 0.2794 0.1778)
						)
						(arc
							(start 0.2794 -0.1778)
							(mid 0.249642 -0.249642)
							(end 0.1778 -0.2794)
						)
					)
					(width 0)
					(fill yes)
				)
			)
		)
	)
)
